(kicad_pcb
	(version 20241229)
	(generator "pcbnew")
	(generator_version "9.0")
	(general
		(thickness 1.6642)
		(legacy_teardrops no)
	)
	(paper "A3")
	(title_block
		(title "PolarFire SoM")
		(date "2025-07-22")
		(rev "1.1.4")
		(company "Antmicro Ltd")
		(comment 1 "www.antmicro.com")
		(comment 9 "footprints 267-270 of 470")
	)
	(layers
		(0 "F.Cu" mixed)
		(4 "In1.Cu" power)
		(6 "In2.Cu" signal)
		(8 "In3.Cu" power)
		(10 "In4.Cu" signal)
		(12 "In5.Cu" power)
		(14 "In6.Cu" power)
		(16 "In7.Cu" signal)
		(18 "In8.Cu" power)
		(20 "In9.Cu" signal)
		(22 "In10.Cu" power)
		(24 "In11.Cu" signal)
		(26 "In12.Cu" signal)
		(2 "B.Cu" mixed)
		(9 "F.Adhes" user "F.Adhesive")
		(11 "B.Adhes" user "B.Adhesive")
		(13 "F.Paste" user)
		(15 "B.Paste" user)
		(5 "F.SilkS" user "F.Silkscreen")
		(7 "B.SilkS" user "B.Silkscreen")
		(1 "F.Mask" user)
		(3 "B.Mask" user)
		(17 "Dwgs.User" user "User.Drawings")
		(19 "Cmts.User" user "User.Comments")
		(21 "Eco1.User" user "User.Eco1")
		(23 "Eco2.User" user "User.Eco2")
		(25 "Edge.Cuts" user)
		(27 "Margin" user)
		(31 "F.CrtYd" user "F.Courtyard")
		(29 "B.CrtYd" user "B.Courtyard")
		(35 "F.Fab" user)
		(33 "B.Fab" user)
	)
	(footprint "antmicro-footprints:SOT-523"
		(layer "B.Cu")
		(at 224.38 129.9 180)
		(property "Reference" "Q7"
			(at -2.02 0.3 180)
			(layer "B.SilkS")
			(effects
				(font
					(size 0.7 0.7)
					(thickness 0.15)
				)
				(justify left bottom mirror)
			)
		)
		(property "Value" "DMG1012T-7"
			(at 0.1 -1.824 0)
			(layer "B.Fab")
			(hide yes)
			(effects
				(font
					(size 0.7 0.7)
					(thickness 0.15)
				)
				(justify left bottom mirror)
			)
		)
		(property "Datasheet" "https://www.diodes.com/assets/Datasheets/ds31783.pdf"
			(at 0 0 180)
			(layer "F.Fab")
			(hide yes)
			(effects
				(font
					(size 1.27 1.27)
					(thickness 0.15)
				)
			)
		)
		(property "Description" "Power MOSFET, N Channel, 20 V, 630 mA, 0.3 ohm, SOT-523, Surface Mount"
			(at 0 0 180)
			(layer "F.Fab")
			(hide yes)
			(effects
				(font
					(size 1.27 1.27)
					(thickness 0.15)
				)
			)
		)
		(property "Author" "Antmicro"
			(at 448.76 259.8 0)
			(layer "B.Fab")
			(hide yes)
			(effects
				(font
					(size 1 1)
					(thickness 0.15)
				)
				(justify mirror)
			)
		)
		(property "License" "Apache-2.0"
			(at 448.76 259.8 0)
			(layer "B.Fab")
			(hide yes)
			(effects
				(font
					(size 1 1)
					(thickness 0.15)
				)
				(justify mirror)
			)
		)
		(property "MPN" "DMG1012T-7"
			(at 448.76 259.8 0)
			(layer "B.Fab")
			(hide yes)
			(effects
				(font
					(size 1 1)
					(thickness 0.15)
				)
				(justify mirror)
			)
		)
		(property "Manufacturer" "Diodes Incorporated"
			(at 448.76 259.8 0)
			(layer "B.Fab")
			(hide yes)
			(effects
				(font
					(size 1 1)
					(thickness 0.15)
				)
				(justify mirror)
			)
		)
		(property "Public" ""
			(at 448.76 259.8 0)
			(layer "B.Fab")
			(hide yes)
			(effects
				(font
					(size 1 1)
					(thickness 0.15)
				)
				(justify mirror)
			)
		)
		(sheetname "/FPGA GPIO/")
		(sheetfile "fpga-gpio.kicad_sch")
		(attr smd)
		(fp_line
			(start -0.277 0.551)
			(end -0.277 0.75)
			(stroke
				(width 0.15)
				(type solid)
			)
			(layer "B.SilkS")
		)
		(fp_line
			(start -0.725 0.551)
			(end -0.277 0.551)
			(stroke
				(width 0.15)
				(type solid)
			)
			(layer "B.SilkS")
		)
		(fp_line
			(start -0.927 0.351)
			(end -0.725 0.551)
			(stroke
				(width 0.15)
				(type solid)
			)
			(layer "B.SilkS")
		)
		(fp_line
			(start -0.927 0.051)
			(end -0.927 0.351)
			(stroke
				(width 0.15)
				(type solid)
			)
			(layer "B.SilkS")
		)
		(fp_circle
			(center -0.9652 -0.9652)
			(end -0.9152 -0.9652)
			(stroke
				(width 0.15)
				(type solid)
			)
			(fill yes)
			(layer "B.SilkS")
		)
		(fp_line
			(start 1.1 1.16)
			(end 1.1 -1.15)
			(stroke
				(width 0.05)
				(type solid)
			)
			(layer "B.CrtYd")
		)
		(fp_line
			(start -1.12 1.16)
			(end 1.1 1.16)
			(stroke
				(width 0.05)
				(type solid)
			)
			(layer "B.CrtYd")
		)
		(fp_line
			(start -1.12 1.16)
			(end -1.12 -1.15)
			(stroke
				(width 0.05)
				(type solid)
			)
			(layer "B.CrtYd")
		)
		(fp_line
			(start -1.12 -1.15)
			(end 1.1 -1.15)
			(stroke
				(width 0.05)
				(type solid)
			)
			(layer "B.CrtYd")
		)
		(fp_line
			(start 0.8 0.425)
			(end 0.8 -0.424)
			(stroke
				(width 0.15)
				(type solid)
			)
			(layer "B.Fab")
		)
		(fp_line
			(start 0.8 0.425)
			(end -0.652 0.425)
			(stroke
				(width 0.15)
				(type solid)
			)
			(layer "B.Fab")
		)
		(fp_line
			(start 0.8 -0.424)
			(end -0.802 -0.424)
			(stroke
				(width 0.15)
				(type solid)
			)
			(layer "B.Fab")
		)
		(fp_line
			(start -0.652 0.425)
			(end -0.802 0.276)
			(stroke
				(width 0.15)
				(type solid)
			)
			(layer "B.Fab")
		)
		(fp_line
			(start -0.802 0.276)
			(end -0.802 -0.424)
			(stroke
				(width 0.15)
				(type solid)
			)
			(layer "B.Fab")
		)
		(fp_circle
			(center -0.9652 -0.9652)
			(end -0.9144 -0.9652)
			(stroke
				(width 0.15)
				(type solid)
			)
			(fill no)
			(layer "B.Fab")
		)
		(fp_text user "${REFERENCE}"
			(at -1.12 -3.824 0)
			(layer "B.Fab")
			(effects
				(font
					(size 0.7 0.7)
					(thickness 0.15)
				)
				(justify left bottom mirror)
			)
		)
		(fp_text user "License: Apache-2.0"
			(at -1.12 -5.024 0)
			(layer "B.Fab")
			(effects
				(font
					(size 0.7 0.7)
					(thickness 0.15)
				)
				(justify left bottom mirror)
			)
		)
		(fp_text user "Author: Antmicro"
			(at -1.12 -6.224 0)
			(layer "B.Fab")
			(effects
				(font
					(size 0.7 0.7)
					(thickness 0.15)
				)
				(justify left bottom mirror)
			)
		)
		(pad "1" smd rect
			(at -0.5 -0.65 180)
			(size 0.4 0.51)
			(layers "B.Cu" "B.Mask" "B.Paste")
			(net 341 "/FPGA GPIO/USER_LED_G")
			(pinfunction "G")
			(pintype "input")
		)
		(pad "2" smd rect
			(at 0.498 -0.65 180)
			(size 0.4 0.51)
			(layers "B.Cu" "B.Mask" "B.Paste")
			(net 417 "GND")
			(pinfunction "S")
			(pintype "passive")
		)
		(pad "3" smd rect
			(at 0 0.652 180)
			(size 0.4 0.51)
			(layers "B.Cu" "B.Mask" "B.Paste")
			(net 541 "Net-(Q7-D)")
			(pinfunction "D")
			(pintype "passive")
		)
	)
	(footprint "antmicro-footprints:C_0402_1005Metric"
		(layer "B.Cu")
		(at 184.8 125.834 -90)
		(descr "Capacitor SMD 0402")
		(tags "capacitor SMD 0402")
		(property "Reference" "C119"
			(at -1.534 -1.4 90)
			(layer "B.SilkS")
			(effects
				(font
					(size 0.7 0.7)
					(thickness 0.15)
				)
				(justify left bottom mirror)
			)
		)
		(property "Value" "C_1u_0402"
			(at -1.022927 -2.155213 90)
			(layer "B.Fab")
			(hide yes)
			(effects
				(font
					(size 0.7 0.7)
					(thickness 0.15)
				)
				(justify left bottom mirror)
			)
		)
		(property "Datasheet" "https://product.tdk.com/en/search/capacitor/ceramic/mlcc/info?part_no=C1005X6S1A105K050BC"
			(at 0 0 270)
			(layer "F.Fab")
			(hide yes)
			(effects
				(font
					(size 1.27 1.27)
					(thickness 0.15)
				)
			)
		)
		(property "Description" "SMD Multilayer Ceramic Capacitor, 1 µF, 10 V, 0402 [1005 Metric], ± 10%, X6S, C"
			(at 0 0 270)
			(layer "F.Fab")
			(hide yes)
			(effects
				(font
					(size 1.27 1.27)
					(thickness 0.15)
				)
			)
		)
		(property "Author" "Antmicro"
			(at 58.966 310.634 0)
			(layer "B.Fab")
			(hide yes)
			(effects
				(font
					(size 1 1)
					(thickness 0.15)
				)
				(justify mirror)
			)
		)
		(property "Dielectric" "X5R"
			(at 58.966 310.634 0)
			(layer "B.Fab")
			(hide yes)
			(effects
				(font
					(size 1 1)
					(thickness 0.15)
				)
				(justify mirror)
			)
		)
		(property "License" "Apache-2.0"
			(at 58.966 310.634 0)
			(layer "B.Fab")
			(hide yes)
			(effects
				(font
					(size 1 1)
					(thickness 0.15)
				)
				(justify mirror)
			)
		)
		(property "MPN" "C1005X6S1A105K050BC"
			(at 58.966 310.634 0)
			(layer "B.Fab")
			(hide yes)
			(effects
				(font
					(size 1 1)
					(thickness 0.15)
				)
				(justify mirror)
			)
		)
		(property "Manufacturer" "TDK"
			(at 58.966 310.634 0)
			(layer "B.Fab")
			(hide yes)
			(effects
				(font
					(size 1 1)
					(thickness 0.15)
				)
				(justify mirror)
			)
		)
		(property "Public" ""
			(at 58.966 310.634 0)
			(layer "B.Fab")
			(hide yes)
			(effects
				(font
					(size 1 1)
					(thickness 0.15)
				)
				(justify mirror)
			)
		)
		(property "Val" "1u"
			(at 58.966 310.634 0)
			(layer "B.Fab")
			(hide yes)
			(effects
				(font
					(size 1 1)
					(thickness 0.15)
				)
				(justify mirror)
			)
		)
		(property "Voltage" "16V"
			(at 58.966 310.634 0)
			(layer "B.Fab")
			(hide yes)
			(effects
				(font
					(size 1 1)
					(thickness 0.15)
				)
				(justify mirror)
			)
		)
		(sheetname "/LPDDR4/")
		(sheetfile "lpddr.kicad_sch")
		(attr smd)
		(fp_rect
			(start -0.925 0.47)
			(end 0.925 -0.47)
			(stroke
				(width 0.05)
				(type default)
			)
			(fill no)
			(layer "B.CrtYd")
		)
		(fp_line
			(start -0.494 0.25)
			(end 0.504 0.25)
			(stroke
				(width 0.15)
				(type solid)
			)
			(layer "B.Fab")
		)
		(fp_line
			(start 0.504 0.25)
			(end 0.504 -0.248)
			(stroke
				(width 0.15)
				(type solid)
			)
			(layer "B.Fab")
		)
		(fp_line
			(start -0.494 -0.248)
			(end -0.494 0.25)
			(stroke
				(width 0.15)
				(type solid)
			)
			(layer "B.Fab")
		)
		(fp_line
			(start 0.504 -0.248)
			(end -0.494 -0.248)
			(stroke
				(width 0.15)
				(type solid)
			)
			(layer "B.Fab")
		)
		(fp_text user "License: Apache-2.0"
			(at -0.939 -5.799 90)
			(layer "B.Fab")
			(effects
				(font
					(size 0.7 0.7)
					(thickness 0.15)
				)
				(justify left bottom mirror)
			)
		)
		(fp_text user "${REFERENCE}"
			(at -0.939 -4.599 90)
			(layer "B.Fab")
			(effects
				(font
					(size 0.7 0.7)
					(thickness 0.15)
				)
				(justify left bottom mirror)
			)
		)
		(fp_text user "Author: Antmicro"
			(at -0.939 -3.399 90)
			(layer "B.Fab")
			(effects
				(font
					(size 0.7 0.7)
					(thickness 0.15)
				)
				(justify left bottom mirror)
			)
		)
		(pad "1" smd roundrect
			(at -0.48 0 270)
			(size 0.59 0.64)
			(layers "B.Cu" "B.Mask" "B.Paste")
			(roundrect_rratio 0.25)
			(net 417 "GND")
			(pintype "passive")
		)
		(pad "2" smd roundrect
			(at 0.48 0 270)
			(size 0.59 0.64)
			(layers "B.Cu" "B.Mask" "B.Paste")
			(roundrect_rratio 0.25)
			(net 48 "+1V8")
			(pintype "passive")
		)
	)
	(footprint "antmicro-footprints:C_0402_1005Metric"
		(layer "B.Cu")
		(at 181.1 140.9875 180)
		(descr "Capacitor SMD 0402")
		(tags "capacitor SMD 0402")
		(property "Reference" "C86"
			(at -11.175 -9.8375 180)
			(layer "B.SilkS")
			(effects
				(font
					(size 0.7 0.7)
					(thickness 0.15)
				)
				(justify left bottom mirror)
			)
		)
		(property "Value" "C_22u_0402"
			(at -1.022927 -2.155213 0)
			(layer "B.Fab")
			(hide yes)
			(effects
				(font
					(size 0.7 0.7)
					(thickness 0.15)
				)
				(justify left bottom mirror)
			)
		)
		(property "Datasheet" "https://www.murata.com/products/productdetail?partno=GRM158R60J226ME01%23"
			(at 0 0 180)
			(layer "F.Fab")
			(hide yes)
			(effects
				(font
					(size 1.27 1.27)
					(thickness 0.15)
				)
			)
		)
		(property "Description" "SMD Multilayer Ceramic Capacitor, 22 uF, 4 V, 0402 [1005 Metric], X6S"
			(at 0 0 180)
			(layer "F.Fab")
			(hide yes)
			(effects
				(font
					(size 1.27 1.27)
					(thickness 0.15)
				)
			)
		)
		(property "Author" "Antmicro"
			(at 362.2 281.975 0)
			(layer "B.Fab")
			(hide yes)
			(effects
				(font
					(size 1 1)
					(thickness 0.15)
				)
				(justify mirror)
			)
		)
		(property "Dielectric" ""
			(at 362.2 281.975 0)
			(layer "B.Fab")
			(hide yes)
			(effects
				(font
					(size 1 1)
					(thickness 0.15)
				)
				(justify mirror)
			)
		)
		(property "License" "Apache-2.0"
			(at 362.2 281.975 0)
			(layer "B.Fab")
			(hide yes)
			(effects
				(font
					(size 1 1)
					(thickness 0.15)
				)
				(justify mirror)
			)
		)
		(property "MPN" "GRM158R60J226ME01D"
			(at 362.2 281.975 0)
			(layer "B.Fab")
			(hide yes)
			(effects
				(font
					(size 1 1)
					(thickness 0.15)
				)
				(justify mirror)
			)
		)
		(property "Manufacturer" "Murata"
			(at 362.2 281.975 0)
			(layer "B.Fab")
			(hide yes)
			(effects
				(font
					(size 1 1)
					(thickness 0.15)
				)
				(justify mirror)
			)
		)
		(property "Public" ""
			(at 362.2 281.975 0)
			(layer "B.Fab")
			(hide yes)
			(effects
				(font
					(size 1 1)
					(thickness 0.15)
				)
				(justify mirror)
			)
		)
		(property "Val" "22u"
			(at 362.2 281.975 0)
			(layer "B.Fab")
			(hide yes)
			(effects
				(font
					(size 1 1)
					(thickness 0.15)
				)
				(justify mirror)
			)
		)
		(property "Voltage" ""
			(at 362.2 281.975 0)
			(layer "B.Fab")
			(hide yes)
			(effects
				(font
					(size 1 1)
					(thickness 0.15)
				)
				(justify mirror)
			)
		)
		(sheetname "/Supply/")
		(sheetfile "supply.kicad_sch")
		(attr smd)
		(fp_rect
			(start -0.925 0.47)
			(end 0.925 -0.47)
			(stroke
				(width 0.05)
				(type default)
			)
			(fill no)
			(layer "B.CrtYd")
		)
		(fp_line
			(start 0.504 0.25)
			(end 0.504 -0.248)
			(stroke
				(width 0.15)
				(type solid)
			)
			(layer "B.Fab")
		)
		(fp_line
			(start 0.504 -0.248)
			(end -0.494 -0.248)
			(stroke
				(width 0.15)
				(type solid)
			)
			(layer "B.Fab")
		)
		(fp_line
			(start -0.494 0.25)
			(end 0.504 0.25)
			(stroke
				(width 0.15)
				(type solid)
			)
			(layer "B.Fab")
		)
		(fp_line
			(start -0.494 -0.248)
			(end -0.494 0.25)
			(stroke
				(width 0.15)
				(type solid)
			)
			(layer "B.Fab")
		)
		(fp_text user "Author: Antmicro"
			(at -0.939 -3.399 0)
			(layer "B.Fab")
			(effects
				(font
					(size 0.7 0.7)
					(thickness 0.15)
				)
				(justify left bottom mirror)
			)
		)
		(fp_text user "${REFERENCE}"
			(at -0.939 -4.599 0)
			(layer "B.Fab")
			(effects
				(font
					(size 0.7 0.7)
					(thickness 0.15)
				)
				(justify left bottom mirror)
			)
		)
		(fp_text user "License: Apache-2.0"
			(at -0.939 -5.799 0)
			(layer "B.Fab")
			(effects
				(font
					(size 0.7 0.7)
					(thickness 0.15)
				)
				(justify left bottom mirror)
			)
		)
		(pad "1" smd roundrect
			(at -0.48 0 180)
			(size 0.59 0.64)
			(layers "B.Cu" "B.Mask" "B.Paste")
			(roundrect_rratio 0.25)
			(net 417 "GND")
			(pintype "passive")
		)
		(pad "2" smd roundrect
			(at 0.48 0 180)
			(size 0.59 0.64)
			(layers "B.Cu" "B.Mask" "B.Paste")
			(roundrect_rratio 0.25)
			(net 90 "+5V")
			(pintype "passive")
		)
	)
	(footprint "antmicro-footprints:C_0402_1005Metric"
		(layer "B.Cu")
		(at 191.25 139.15 135)
		(descr "Capacitor SMD 0402")
		(tags "capacitor SMD 0402")
		(property "Reference" "C61"
			(at 3.464823 -0.883883 135)
			(layer "B.SilkS")
			(effects
				(font
					(size 0.7 0.7)
					(thickness 0.15)
				)
				(justify right bottom mirror)
			)
		)
		(property "Value" "C_100n_0402"
			(at -1.022927 -2.155213 135)
			(layer "B.Fab")
			(hide yes)
			(effects
				(font
					(size 0.7 0.7)
					(thickness 0.15)
				)
				(justify right bottom mirror)
			)
		)
		(property "Datasheet" "https://www.murata.com/products/productdetail?partno=GRM155R61H104KE14%23"
			(at 0 0 135)
			(layer "F.Fab")
			(hide yes)
			(effects
				(font
					(size 1.27 1.27)
					(thickness 0.15)
				)
			)
		)
		(property "Description" "SMD Multilayer Ceramic Capacitor, 0.1 µF, 50 V, 0402 [1005 Metric], ± 10%, X5R, GRM Series"
			(at 0 0 135)
			(layer "F.Fab")
			(hide yes)
			(effects
				(font
					(size 1.27 1.27)
					(thickness 0.15)
				)
			)
		)
		(property "Author" "Antmicro"
			(at 424.878081 102.309737 0)
			(layer "B.Fab")
			(hide yes)
			(effects
				(font
					(size 1 1)
					(thickness 0.15)
				)
				(justify mirror)
			)
		)
		(property "Dielectric" "X5R"
			(at 424.878081 102.309737 0)
			(layer "B.Fab")
			(hide yes)
			(effects
				(font
					(size 1 1)
					(thickness 0.15)
				)
				(justify mirror)
			)
		)
		(property "License" "Apache-2.0"
			(at 424.878081 102.309737 0)
			(layer "B.Fab")
			(hide yes)
			(effects
				(font
					(size 1 1)
					(thickness 0.15)
				)
				(justify mirror)
			)
		)
		(property "MPN" "GRM155R61H104KE14D"
			(at 424.878081 102.309737 0)
			(layer "B.Fab")
			(hide yes)
			(effects
				(font
					(size 1 1)
					(thickness 0.15)
				)
				(justify mirror)
			)
		)
		(property "Manufacturer" "Murata"
			(at 424.878081 102.309737 0)
			(layer "B.Fab")
			(hide yes)
			(effects
				(font
					(size 1 1)
					(thickness 0.15)
				)
				(justify mirror)
			)
		)
		(property "Public" ""
			(at 424.878081 102.309737 0)
			(layer "B.Fab")
			(hide yes)
			(effects
				(font
					(size 1 1)
					(thickness 0.15)
				)
				(justify mirror)
			)
		)
		(property "Val" "100n"
			(at 424.878081 102.309737 0)
			(layer "B.Fab")
			(hide yes)
			(effects
				(font
					(size 1 1)
					(thickness 0.15)
				)
				(justify mirror)
			)
		)
		(property "Voltage" "50V"
			(at 424.878081 102.309737 0)
			(layer "B.Fab")
			(hide yes)
			(effects
				(font
					(size 1 1)
					(thickness 0.15)
				)
				(justify mirror)
			)
		)
		(sheetname "/FPGA Supply/")
		(sheetfile "fpga-supply.kicad_sch")
		(attr smd)
		(fp_poly
			(pts
				(xy -0.925 0.47) (xy 0.925 0.47) (xy 0.925 -0.47) (xy -0.925 -0.47)
			)
			(stroke
				(width 0.05)
				(type default)
			)
			(fill no)
			(layer "B.CrtYd")
		)
		(fp_line
			(start 0.504 -0.248)
			(end -0.494 -0.248)
			(stroke
				(width 0.15)
				(type solid)
			)
			(layer "B.Fab")
		)
		(fp_line
			(start 0.504 0.25)
			(end 0.504 -0.248)
			(stroke
				(width 0.15)
				(type solid)
			)
			(layer "B.Fab")
		)
		(fp_line
			(start -0.494 -0.248)
			(end -0.494 0.25)
			(stroke
				(width 0.15)
				(type solid)
			)
			(layer "B.Fab")
		)
		(fp_line
			(start -0.494 0.25)
			(end 0.504 0.25)
			(stroke
				(width 0.15)
				(type solid)
			)
			(layer "B.Fab")
		)
		(fp_text user "Author: Antmicro"
			(at -0.939 -3.399 315)
			(layer "B.Fab")
			(effects
				(font
					(size 0.7 0.7)
					(thickness 0.15)
				)
				(justify left bottom mirror)
			)
		)
		(fp_text user "${REFERENCE}"
			(at -0.939 -4.599 315)
			(layer "B.Fab")
			(effects
				(font
					(size 0.7 0.7)
					(thickness 0.15)
				)
				(justify left bottom mirror)
			)
		)
		(fp_text user "License: Apache-2.0"
			(at -0.939 -5.799 315)
			(layer "B.Fab")
			(effects
				(font
					(size 0.7 0.7)
					(thickness 0.15)
				)
				(justify left bottom mirror)
			)
		)
		(pad "1" smd roundrect
			(at -0.48 0 135)
			(size 0.59 0.64)
			(layers "B.Cu" "B.Mask" "B.Paste")
			(roundrect_rratio 0.25)
			(net 417 "GND")
			(pintype "passive")
		)
		(pad "2" smd roundrect
			(at 0.48 0 135)
			(size 0.59 0.64)
			(layers "B.Cu" "B.Mask" "B.Paste")
			(roundrect_rratio 0.25)
			(net 48 "+1V8")
			(pintype "passive")
		)
	)
)
